(kicad_pcb
	(version 20260206)
	(generator "pcbnew")
	(generator_version "10.0")
	(general
		(thickness 1.6)
		(legacy_teardrops no)
	)
	(paper "A4")
	(title_block
		(title "Bryce Canyon_IOM_M2_16342-2_OCP.brd")
		(comment 1 "Bryce Canyon / footprints 266-274 of 1146")
	)
	(layers
		(0 "F.Cu" signal "TOP")
		(4 "In1.Cu" signal "L2GND")
		(6 "In2.Cu" signal "L3")
		(8 "In3.Cu" signal "L4VCC")
		(10 "In4.Cu" signal "L5VCC")
		(12 "In5.Cu" signal "L6")
		(14 "In6.Cu" signal "L7GND")
		(2 "B.Cu" signal "BOTTOM")
		(9 "F.Adhes" user "F.Adhesive")
		(11 "B.Adhes" user "B.Adhesive")
		(13 "F.Paste" user "Package Geometry/Pastemask Top")
		(15 "B.Paste" user "Package Geometry/Pastemask Bottom")
		(5 "F.SilkS" user "Ref Des/Silkscreen Top")
		(7 "B.SilkS" user "Ref Des/Silkscreen Bottom")
		(1 "F.Mask" user "Board Geometry/Soldermask Top")
		(3 "B.Mask" user "Board Geometry/Soldermask Bottom")
		(17 "Dwgs.User" user "User.Drawings")
		(19 "Cmts.User" user "User.Comments")
		(21 "Eco1.User" user "User.Eco1")
		(23 "Eco2.User" user "User.Eco2")
		(25 "Edge.Cuts" user "Board Geometry/Outline")
		(27 "Margin" user)
		(31 "F.CrtYd" user "Package Geometry/Place Bound Top")
		(29 "B.CrtYd" user "Package Geometry/Place Bound Bottom")
		(35 "F.Fab" user "Ref Des/Assembly Top")
		(33 "B.Fab" user "Ref Des/Assembly Bottom")
	)
	(footprint ""
		(layer "F.Cu")
		(at 35.246818 -136.59993 90)
		(property "Reference" "R351"
			(at 0 0 90)
			(layer "F.SilkS")
			(hide yes)
			(effects
				(font
					(size 1.27 1.27)
				)
			)
		)
		(property "Value" "10KR2F-2-GP"
			(at 0.064008 -3.993896 90)
			(unlocked yes)
			(layer "F.Fab")
			(hide yes)
			(effects
				(font
					(size 1.016 1.016)
					(thickness 0.1524)
				)
			)
		)
		(property "Device Type" "R402H16"
			(at 0.064008 -5.517896 90)
			(unlocked yes)
			(layer "F.Fab")
			(hide yes)
			(effects
				(font
					(size 1.016 1.016)
					(thickness 0.1524)
				)
			)
		)
		(duplicate_pad_numbers_are_jumpers no)
		(fp_line
			(start 0.508 -0.9398)
			(end -0.508 -0.9398)
			(stroke
				(width 0.1524)
				(type default)
			)
			(layer "F.SilkS")
		)
		(fp_line
			(start -0.508 -0.9398)
			(end -0.508 0.9398)
			(stroke
				(width 0.1524)
				(type default)
			)
			(layer "F.SilkS")
		)
		(fp_rect
			(start -0.508 0.9398)
			(end 0.508 -0.9398)
			(stroke
				(width 0)
				(type default)
			)
			(fill no)
			(layer "F.CrtYd")
		)
		(fp_rect
			(start -0.508 0.9398)
			(end 0.508 -0.9398)
			(stroke
				(width 0)
				(type default)
			)
			(fill no)
			(layer "F.Fab")
		)
		(pad "1" smd custom
			(at 0 -0.4445 90)
			(size 0.1397 0.1397)
			(layers "F.Cu" "F.Mask" "F.Paste")
			(net "GND")
			(options
				(clearance outline)
				(anchor circle)
			)
			(primitives
				(gr_poly
					(pts
						(arc
							(start -0.1778 -0.2794)
							(mid -0.249642 -0.249642)
							(end -0.2794 -0.1778)
						)
						(arc
							(start -0.2794 0.1778)
							(mid -0.249642 0.249642)
							(end -0.1778 0.2794)
						)
						(arc
							(start 0.1778 0.2794)
							(mid 0.249642 0.249642)
							(end 0.2794 0.1778)
						)
						(arc
							(start 0.2794 -0.1778)
							(mid 0.249642 -0.249642)
							(end 0.1778 -0.2794)
						)
					)
					(width 0)
					(fill yes)
				)
			)
		)
		(pad "2" smd custom
			(at 0 0.4445 90)
			(size 0.1397 0.1397)
			(layers "F.Cu" "F.Mask" "F.Paste")
			(net "PECI")
			(options
				(clearance outline)
				(anchor circle)
			)
			(primitives
				(gr_poly
					(pts
						(arc
							(start -0.1778 -0.2794)
							(mid -0.249642 -0.249642)
							(end -0.2794 -0.1778)
						)
						(arc
							(start -0.2794 0.1778)
							(mid -0.249642 0.249642)
							(end -0.1778 0.2794)
						)
						(arc
							(start 0.1778 0.2794)
							(mid 0.249642 0.249642)
							(end 0.2794 0.1778)
						)
						(arc
							(start 0.2794 -0.1778)
							(mid 0.249642 -0.249642)
							(end 0.1778 -0.2794)
						)
					)
					(width 0)
					(fill yes)
				)
			)
		)
	)
	(footprint ""
		(layer "F.Cu")
		(at 213.098888 -94.683326)
		(property "Reference" "C648"
			(at 0 0 0)
			(layer "F.SilkS")
			(hide yes)
			(effects
				(font
					(size 1.27 1.27)
				)
			)
		)
		(property "Value" "SC68P50V2JN-2-GP"
			(at 1.1811 -2.7051 0)
			(unlocked yes)
			(layer "F.Fab")
			(hide yes)
			(effects
				(font
					(size 1.016 1.016)
					(thickness 0.1524)
				)
			)
		)
		(property "Device Type" "C402H22"
			(at 1.1811 -4.2291 0)
			(unlocked yes)
			(layer "F.Fab")
			(hide yes)
			(effects
				(font
					(size 1.016 1.016)
					(thickness 0.1524)
				)
			)
		)
		(duplicate_pad_numbers_are_jumpers no)
		(fp_rect
			(start -0.4318 0.9525)
			(end 0.4318 -0.9525)
			(stroke
				(width 0)
				(type default)
			)
			(fill no)
			(layer "F.CrtYd")
		)
		(fp_rect
			(start -0.4318 0.9525)
			(end 0.4318 -0.9525)
			(stroke
				(width 0)
				(type default)
			)
			(fill no)
			(layer "F.Fab")
		)
		(pad "1" smd custom
			(at 0 -0.4445)
			(size 0.1524 0.1524)
			(layers "F.Cu" "F.Mask" "F.Paste")
			(net "P3V3_M2_VFB")
			(options
				(clearance outline)
				(anchor circle)
			)
			(primitives
				(gr_poly
					(pts
						(arc
							(start 0.3048 -0.2032)
							(mid 0.275042 -0.275042)
							(end 0.2032 -0.3048)
						)
						(arc
							(start -0.2032 -0.3048)
							(mid -0.275042 -0.275042)
							(end -0.3048 -0.2032)
						)
						(arc
							(start -0.3048 0.2032)
							(mid -0.275042 0.275042)
							(end -0.2032 0.3048)
						)
						(arc
							(start 0.2032 0.3048)
							(mid 0.275042 0.275042)
							(end 0.3048 0.2032)
						)
					)
					(width 0)
					(fill yes)
				)
			)
		)
		(pad "2" smd custom
			(at 0 0.4445)
			(size 0.1524 0.1524)
			(layers "F.Cu" "F.Mask" "F.Paste")
			(net "P3V3_M2_VFB_R")
			(options
				(clearance outline)
				(anchor circle)
			)
			(primitives
				(gr_poly
					(pts
						(arc
							(start 0.3048 -0.2032)
							(mid 0.275042 -0.275042)
							(end 0.2032 -0.3048)
						)
						(arc
							(start -0.2032 -0.3048)
							(mid -0.275042 -0.275042)
							(end -0.3048 -0.2032)
						)
						(arc
							(start -0.3048 0.2032)
							(mid -0.275042 0.275042)
							(end -0.2032 0.3048)
						)
						(arc
							(start 0.2032 0.3048)
							(mid 0.275042 0.275042)
							(end 0.3048 0.2032)
						)
					)
					(width 0)
					(fill yes)
				)
			)
		)
	)
	(footprint ""
		(layer "F.Cu")
		(at 212.331046 -122.65406)
		(property "Reference" "TP211"
			(at 0 0 0)
			(layer "F.SilkS")
			(hide yes)
			(effects
				(font
					(size 1.27 1.27)
				)
			)
		)
		(property "Value" "TPAD28-2-GP"
			(at -0.0127 -1.6637 0)
			(unlocked yes)
			(layer "F.Fab")
			(hide yes)
			(effects
				(font
					(size 1.016 1.016)
					(thickness 0.1524)
				)
			)
		)
		(property "Device Type" "TPAD28"
			(at -0.0127 -3.1877 0)
			(unlocked yes)
			(layer "F.Fab")
			(hide yes)
			(effects
				(font
					(size 1.016 1.016)
					(thickness 0.1524)
				)
			)
		)
		(duplicate_pad_numbers_are_jumpers no)
		(fp_poly
			(pts
				(arc
					(start 0.3556 0)
					(mid -0.3556 0)
					(end 0.3556 0)
				)
			)
			(stroke
				(width 0)
				(type default)
			)
			(fill no)
			(layer "F.CrtYd")
		)
		(fp_poly
			(pts
				(arc
					(start 0.6096 0)
					(mid -0.6096 0)
					(end 0.6096 0)
				)
			)
			(stroke
				(width 0)
				(type default)
			)
			(fill no)
			(layer "F.Fab")
		)
		(pad "1" smd circle
			(at 0 0)
			(size 0.7112 0.7112)
			(layers "F.Cu" "F.Mask" "F.Paste")
			(net "TP_M2_1_MFG_CLK")
		)
	)
	(footprint ""
		(layer "F.Cu")
		(at 59.436 -158.369)
		(property "Reference" "R396"
			(at 0 0 0)
			(layer "F.SilkS")
			(hide yes)
			(effects
				(font
					(size 1.27 1.27)
				)
			)
		)
		(property "Value" "4K7R2F-GP"
			(at 0.064008 -3.993896 0)
			(unlocked yes)
			(layer "F.Fab")
			(hide yes)
			(effects
				(font
					(size 1.016 1.016)
					(thickness 0.1524)
				)
			)
		)
		(property "Device Type" "R402H16"
			(at 0.064008 -5.517896 0)
			(unlocked yes)
			(layer "F.Fab")
			(hide yes)
			(effects
				(font
					(size 1.016 1.016)
					(thickness 0.1524)
				)
			)
		)
		(duplicate_pad_numbers_are_jumpers no)
		(fp_line
			(start -0.508 -0.9398)
			(end -0.508 0.9398)
			(stroke
				(width 0.1524)
				(type default)
			)
			(layer "F.SilkS")
		)
		(fp_line
			(start 0.508 -0.9398)
			(end -0.508 -0.9398)
			(stroke
				(width 0.1524)
				(type default)
			)
			(layer "F.SilkS")
		)
		(fp_rect
			(start -0.508 0.9398)
			(end 0.508 -0.9398)
			(stroke
				(width 0)
				(type default)
			)
			(fill no)
			(layer "F.CrtYd")
		)
		(fp_rect
			(start -0.508 0.9398)
			(end 0.508 -0.9398)
			(stroke
				(width 0)
				(type default)
			)
			(fill no)
			(layer "F.Fab")
		)
		(pad "1" smd custom
			(at 0 -0.4445)
			(size 0.1397 0.1397)
			(layers "F.Cu" "F.Mask" "F.Paste")
			(net "GND")
			(options
				(clearance outline)
				(anchor circle)
			)
			(primitives
				(gr_poly
					(pts
						(arc
							(start -0.1778 -0.2794)
							(mid -0.249642 -0.249642)
							(end -0.2794 -0.1778)
						)
						(arc
							(start -0.2794 0.1778)
							(mid -0.249642 0.249642)
							(end -0.1778 0.2794)
						)
						(arc
							(start 0.1778 0.2794)
							(mid 0.249642 0.249642)
							(end 0.2794 0.1778)
						)
						(arc
							(start 0.2794 -0.1778)
							(mid 0.249642 -0.249642)
							(end 0.1778 -0.2794)
						)
					)
					(width 0)
					(fill yes)
				)
			)
		)
		(pad "2" smd custom
			(at 0 0.4445)
			(size 0.1397 0.1397)
			(layers "F.Cu" "F.Mask" "F.Paste")
			(net "MAC2_TXD0")
			(options
				(clearance outline)
				(anchor circle)
			)
			(primitives
				(gr_poly
					(pts
						(arc
							(start -0.1778 -0.2794)
							(mid -0.249642 -0.249642)
							(end -0.2794 -0.1778)
						)
						(arc
							(start -0.2794 0.1778)
							(mid -0.249642 0.249642)
							(end -0.1778 0.2794)
						)
						(arc
							(start 0.1778 0.2794)
							(mid 0.249642 0.249642)
							(end 0.2794 0.1778)
						)
						(arc
							(start 0.2794 -0.1778)
							(mid 0.249642 -0.249642)
							(end 0.1778 -0.2794)
						)
					)
					(width 0)
					(fill yes)
				)
			)
		)
	)
	(footprint ""
		(layer "F.Cu")
		(at 83.359498 -88.535764 90)
		(property "Reference" "VIA13"
			(at 0 0 90)
			(layer "F.SilkS")
			(hide yes)
			(effects
				(font
					(size 1.27 1.27)
				)
			)
		)
		(property "Value" "85OHM-8L-1D6MM-L16L18-GP"
			(at 4.064 0.6096 90)
			(unlocked yes)
			(layer "F.Fab")
			(hide yes)
			(effects
				(font
					(size 1.016 1.016)
					(thickness 0.1524)
				)
			)
		)
		(property "Device Type" "VIA-PCIE-4P-368076"
			(at 4.064 -0.9144 90)
			(unlocked yes)
			(layer "F.Fab")
			(hide yes)
			(effects
				(font
					(size 1.016 1.016)
					(thickness 0.1524)
				)
			)
		)
		(duplicate_pad_numbers_are_jumpers no)
		(fp_rect
			(start -1.8415 0.381)
			(end 1.8415 -0.381)
			(stroke
				(width 0)
				(type default)
			)
			(fill no)
			(layer "F.CrtYd")
		)
		(fp_rect
			(start -1.8415 0.381)
			(end 1.8415 -0.381)
			(stroke
				(width 0)
				(type default)
			)
			(fill no)
			(layer "F.Fab")
		)
		(pad "1" thru_hole circle
			(at -1.4605 0 90)
			(size 0.508 0.508)
			(drill 0.254)
			(layers "*.Cu" "*.Mask")
			(remove_unused_layers no)
			(net "GND")
			(clearance 0.127)
			(thermal_gap 0.127)
		)
		(pad "2" thru_hole circle
			(at -0.4445 0 90)
			(size 0.508 0.508)
			(drill 0.254)
			(layers "*.Cu" "*.Mask")
			(remove_unused_layers no)
			(net "PCIE_IOM_TO_COMP_21_DP")
			(clearance 0.127)
			(thermal_gap 0.127)
		)
		(pad "3" thru_hole circle
			(at 0.4445 0 90)
			(size 0.508 0.508)
			(drill 0.254)
			(layers "*.Cu" "*.Mask")
			(remove_unused_layers no)
			(net "PCIE_IOM_TO_COMP_21_DN")
			(clearance 0.127)
			(thermal_gap 0.127)
		)
		(pad "4" thru_hole circle
			(at 1.4605 0 90)
			(size 0.508 0.508)
			(drill 0.254)
			(layers "*.Cu" "*.Mask")
			(remove_unused_layers no)
			(net "GND")
			(clearance 0.127)
			(thermal_gap 0.127)
		)
	)
	(footprint ""
		(layer "F.Cu")
		(at 52.485544 -157.136846)
		(property "Reference" "TP210"
			(at 0 0 0)
			(layer "F.SilkS")
			(hide yes)
			(effects
				(font
					(size 1.27 1.27)
				)
			)
		)
		(property "Value" "TPAD28-2-GP"
			(at -0.0127 -1.6637 0)
			(unlocked yes)
			(layer "F.Fab")
			(hide yes)
			(effects
				(font
					(size 1.016 1.016)
					(thickness 0.1524)
				)
			)
		)
		(property "Device Type" "TPAD28"
			(at -0.0127 -3.1877 0)
			(unlocked yes)
			(layer "F.Fab")
			(hide yes)
			(effects
				(font
					(size 1.016 1.016)
					(thickness 0.1524)
				)
			)
		)
		(duplicate_pad_numbers_are_jumpers no)
		(fp_poly
			(pts
				(arc
					(start 0.3556 0)
					(mid -0.3556 0)
					(end 0.3556 0)
				)
			)
			(stroke
				(width 0)
				(type default)
			)
			(fill no)
			(layer "F.CrtYd")
		)
		(fp_poly
			(pts
				(arc
					(start 0.6096 0)
					(mid -0.6096 0)
					(end 0.6096 0)
				)
			)
			(stroke
				(width 0)
				(type default)
			)
			(fill no)
			(layer "F.Fab")
		)
		(pad "1" smd circle
			(at 0 0)
			(size 0.7112 0.7112)
			(layers "F.Cu" "F.Mask" "F.Paste")
			(net "ADC_P0V975")
		)
	)
	(footprint ""
		(layer "F.Cu")
		(at 226.515676 -102.169214 180)
		(property "Reference" "C672"
			(at 0 0 180)
			(layer "F.SilkS")
			(hide yes)
			(effects
				(font
					(size 1.27 1.27)
				)
			)
		)
		(property "Value" "SC10U16V5KX-7-GP-U"
			(at -0.0762 -6.1214 180)
			(unlocked yes)
			(layer "F.Fab")
			(hide yes)
			(effects
				(font
					(size 1.016 1.016)
					(thickness 0.1524)
				)
			)
		)
		(property "Device Type" "C805H58"
			(at -0.0762 -8.1534 180)
			(unlocked yes)
			(layer "F.Fab")
			(hide yes)
			(effects
				(font
					(size 1.016 1.016)
					(thickness 0.1524)
				)
			)
		)
		(duplicate_pad_numbers_are_jumpers no)
		(fp_line
			(start 0.635 0)
			(end -0.635 0)
			(stroke
				(width 0.508)
				(type default)
			)
			(layer "F.SilkS")
		)
		(fp_rect
			(start -0.9652 1.778)
			(end 0.9652 -1.778)
			(stroke
				(width 0)
				(type default)
			)
			(fill no)
			(layer "F.CrtYd")
		)
		(fp_poly
			(pts
				(xy -0.9652 -1.778) (xy 0.9652 -1.778) (xy 0.9652 1.778) (xy -0.9652 1.778)
			)
			(stroke
				(width 0)
				(type default)
			)
			(fill no)
			(layer "F.Fab")
		)
		(pad "1" smd rect
			(at 0 -0.9652 180)
			(size 1.397 1.143)
			(layers "F.Cu" "F.Mask" "F.Paste")
			(net "P12V_STBY_VIN_U81")
		)
		(pad "2" smd rect
			(at 0 0.9652 180)
			(size 1.397 1.143)
			(layers "F.Cu" "F.Mask" "F.Paste")
			(net "GND")
		)
	)
	(footprint ""
		(layer "F.Cu")
		(at 51.689 -131.7244)
		(property "Reference" "R148"
			(at 0 0 0)
			(layer "F.SilkS")
			(hide yes)
			(effects
				(font
					(size 1.27 1.27)
				)
			)
		)
		(property "Value" "100KR2F-L1-GP"
			(at 0.064008 -3.993896 0)
			(unlocked yes)
			(layer "F.Fab")
			(hide yes)
			(effects
				(font
					(size 1.016 1.016)
					(thickness 0.1524)
				)
			)
		)
		(property "Device Type" "R402H16"
			(at 0.064008 -5.517896 0)
			(unlocked yes)
			(layer "F.Fab")
			(hide yes)
			(effects
				(font
					(size 1.016 1.016)
					(thickness 0.1524)
				)
			)
		)
		(duplicate_pad_numbers_are_jumpers no)
		(fp_line
			(start -0.508 -0.9398)
			(end -0.508 0.9398)
			(stroke
				(width 0.1524)
				(type default)
			)
			(layer "F.SilkS")
		)
		(fp_line
			(start 0.508 -0.9398)
			(end -0.508 -0.9398)
			(stroke
				(width 0.1524)
				(type default)
			)
			(layer "F.SilkS")
		)
		(fp_rect
			(start -0.508 0.9398)
			(end 0.508 -0.9398)
			(stroke
				(width 0)
				(type default)
			)
			(fill no)
			(layer "F.CrtYd")
		)
		(fp_rect
			(start -0.508 0.9398)
			(end 0.508 -0.9398)
			(stroke
				(width 0)
				(type default)
			)
			(fill no)
			(layer "F.Fab")
		)
		(pad "1" smd custom
			(at 0 -0.4445)
			(size 0.1397 0.1397)
			(layers "F.Cu" "F.Mask" "F.Paste")
			(net "IRQ_CPU_SERIAL")
			(options
				(clearance outline)
				(anchor circle)
			)
			(primitives
				(gr_poly
					(pts
						(arc
							(start -0.1778 -0.2794)
							(mid -0.249642 -0.249642)
							(end -0.2794 -0.1778)
						)
						(arc
							(start -0.2794 0.1778)
							(mid -0.249642 0.249642)
							(end -0.1778 0.2794)
						)
						(arc
							(start 0.1778 0.2794)
							(mid 0.249642 0.249642)
							(end 0.2794 0.1778)
						)
						(arc
							(start 0.2794 -0.1778)
							(mid 0.249642 -0.249642)
							(end 0.1778 -0.2794)
						)
					)
					(width 0)
					(fill yes)
				)
			)
		)
		(pad "2" smd custom
			(at 0 0.4445)
			(size 0.1397 0.1397)
			(layers "F.Cu" "F.Mask" "F.Paste")
			(net "GND")
			(options
				(clearance outline)
				(anchor circle)
			)
			(primitives
				(gr_poly
					(pts
						(arc
							(start -0.1778 -0.2794)
							(mid -0.249642 -0.249642)
							(end -0.2794 -0.1778)
						)
						(arc
							(start -0.2794 0.1778)
							(mid -0.249642 0.249642)
							(end -0.1778 0.2794)
						)
						(arc
							(start 0.1778 0.2794)
							(mid 0.249642 0.249642)
							(end 0.2794 0.1778)
						)
						(arc
							(start 0.2794 -0.1778)
							(mid 0.249642 -0.249642)
							(end 0.1778 -0.2794)
						)
					)
					(width 0)
					(fill yes)
				)
			)
		)
	)
	(footprint ""
		(layer "F.Cu")
		(at 216.069672 -52.797456 90)
		(property "Reference" "R475"
			(at 0 0 90)
			(layer "F.SilkS")
			(hide yes)
			(effects
				(font
					(size 1.27 1.27)
				)
			)
		)
		(property "Value" "57K6R2D-GP"
			(at 0.064008 -3.993896 90)
			(unlocked yes)
			(layer "F.Fab")
			(hide yes)
			(effects
				(font
					(size 1.016 1.016)
					(thickness 0.1524)
				)
			)
		)
		(property "Device Type" "R402H16"
			(at 0.064008 -5.517896 90)
			(unlocked yes)
			(layer "F.Fab")
			(hide yes)
			(effects
				(font
					(size 1.016 1.016)
					(thickness 0.1524)
				)
			)
		)
		(duplicate_pad_numbers_are_jumpers no)
		(fp_line
			(start 0.508 -0.9398)
			(end -0.508 -0.9398)
			(stroke
				(width 0.1524)
				(type default)
			)
			(layer "F.SilkS")
		)
		(fp_line
			(start -0.508 -0.9398)
			(end -0.508 0.9398)
			(stroke
				(width 0.1524)
				(type default)
			)
			(layer "F.SilkS")
		)
		(fp_rect
			(start -0.508 0.9398)
			(end 0.508 -0.9398)
			(stroke
				(width 0)
				(type default)
			)
			(fill no)
			(layer "F.CrtYd")
		)
		(fp_rect
			(start -0.508 0.9398)
			(end 0.508 -0.9398)
			(stroke
				(width 0)
				(type default)
			)
			(fill no)
			(layer "F.Fab")
		)
		(pad "1" smd custom
			(at 0 -0.4445 90)
			(size 0.1397 0.1397)
			(layers "F.Cu" "F.Mask" "F.Paste")
			(net "AGND_P5V")
			(options
				(clearance outline)
				(anchor circle)
			)
			(primitives
				(gr_poly
					(pts
						(arc
							(start -0.1778 -0.2794)
							(mid -0.249642 -0.249642)
							(end -0.2794 -0.1778)
						)
						(arc
							(start -0.2794 0.1778)
							(mid -0.249642 0.249642)
							(end -0.1778 0.2794)
						)
						(arc
							(start 0.1778 0.2794)
							(mid 0.249642 0.249642)
							(end 0.2794 0.1778)
						)
						(arc
							(start 0.2794 -0.1778)
							(mid 0.249642 -0.249642)
							(end 0.1778 -0.2794)
						)
					)
					(width 0)
					(fill yes)
				)
			)
		)
		(pad "2" smd custom
			(at 0 0.4445 90)
			(size 0.1397 0.1397)
			(layers "F.Cu" "F.Mask" "F.Paste")
			(net "P5V_TRIP")
			(options
				(clearance outline)
				(anchor circle)
			)
			(primitives
				(gr_poly
					(pts
						(arc
							(start -0.1778 -0.2794)
							(mid -0.249642 -0.249642)
							(end -0.2794 -0.1778)
						)
						(arc
							(start -0.2794 0.1778)
							(mid -0.249642 0.249642)
							(end -0.1778 0.2794)
						)
						(arc
							(start 0.1778 0.2794)
							(mid 0.249642 0.249642)
							(end 0.2794 0.1778)
						)
						(arc
							(start 0.2794 -0.1778)
							(mid 0.249642 -0.249642)
							(end 0.1778 -0.2794)
						)
					)
					(width 0)
					(fill yes)
				)
			)
		)
	)
)
